(kicad_pcb
	(version 20260206)
	(generator "pcbnew")
	(generator_version "10.0")
	(general
		(thickness 1.6)
		(legacy_teardrops no)
	)
	(paper "A4")
	(title_block
		(title "Bryce Canyon_IOM_IOC_16318-2_OCP.brd")
		(comment 1 "Bryce Canyon / footprints 676-684 of 1605")
	)
	(layers
		(0 "F.Cu" signal "TOP")
		(4 "In1.Cu" signal "L2GND")
		(6 "In2.Cu" signal "L3")
		(8 "In3.Cu" signal "L4VCC")
		(10 "In4.Cu" signal "L5VCC")
		(12 "In5.Cu" signal "L6")
		(14 "In6.Cu" signal "L7GND")
		(2 "B.Cu" signal "BOTTOM")
		(9 "F.Adhes" user "F.Adhesive")
		(11 "B.Adhes" user "B.Adhesive")
		(13 "F.Paste" user "Package Geometry/Pastemask Top")
		(15 "B.Paste" user "Package Geometry/Pastemask Bottom")
		(5 "F.SilkS" user "Ref Des/Silkscreen Top")
		(7 "B.SilkS" user "Ref Des/Silkscreen Bottom")
		(1 "F.Mask" user "Board Geometry/Soldermask Top")
		(3 "B.Mask" user "Board Geometry/Soldermask Bottom")
		(17 "Dwgs.User" user "User.Drawings")
		(19 "Cmts.User" user "User.Comments")
		(21 "Eco1.User" user "User.Eco1")
		(23 "Eco2.User" user "User.Eco2")
		(25 "Edge.Cuts" user "Board Geometry/Outline")
		(27 "Margin" user)
		(31 "F.CrtYd" user "Package Geometry/Place Bound Top")
		(29 "B.CrtYd" user "Package Geometry/Place Bound Bottom")
		(35 "F.Fab" user "Ref Des/Assembly Top")
		(33 "B.Fab" user "Ref Des/Assembly Bottom")
	)
	(footprint ""
		(layer "F.Cu")
		(at 184.1246 -124.714 180)
		(property "Reference" "C277"
			(at 0 0 180)
			(layer "F.SilkS")
			(hide yes)
			(effects
				(font
					(size 1.27 1.27)
				)
			)
		)
		(property "Value" "SC1U25V3KX-GP"
			(at 0 -2.8194 180)
			(unlocked yes)
			(layer "F.Fab")
			(hide yes)
			(effects
				(font
					(size 1.016 1.016)
					(thickness 0.1524)
				)
			)
		)
		(property "Device Type" "C603H36"
			(at 0 -4.3434 180)
			(unlocked yes)
			(layer "F.Fab")
			(hide yes)
			(effects
				(font
					(size 1.016 1.016)
					(thickness 0.1524)
				)
			)
		)
		(duplicate_pad_numbers_are_jumpers no)
		(fp_line
			(start 0.508 0)
			(end -0.508 0)
			(stroke
				(width 0.2032)
				(type default)
			)
			(layer "F.SilkS")
		)
		(fp_rect
			(start -0.5842 1.3335)
			(end 0.5842 -1.3335)
			(stroke
				(width 0)
				(type default)
			)
			(fill no)
			(layer "F.CrtYd")
		)
		(fp_rect
			(start -0.5842 1.3335)
			(end 0.5842 -1.3335)
			(stroke
				(width 0)
				(type default)
			)
			(fill no)
			(layer "F.Fab")
		)
		(pad "1" smd custom
			(at 0 -0.762 180)
			(size 0.2159 0.2159)
			(layers "F.Cu" "F.Mask" "F.Paste")
			(net "VT235_AVDD")
			(options
				(clearance outline)
				(anchor circle)
			)
			(primitives
				(gr_poly
					(pts
						(arc
							(start -0.3302 -0.4318)
							(mid -0.402042 -0.402042)
							(end -0.4318 -0.3302)
						)
						(arc
							(start -0.4318 0.3302)
							(mid -0.402042 0.402042)
							(end -0.3302 0.4318)
						)
						(arc
							(start 0.3302 0.4318)
							(mid 0.402042 0.402042)
							(end 0.4318 0.3302)
						)
						(arc
							(start 0.4318 -0.3302)
							(mid 0.402042 -0.402042)
							(end 0.3302 -0.4318)
						)
					)
					(width 0)
					(fill yes)
				)
			)
		)
		(pad "2" smd custom
			(at 0 0.762 180)
			(size 0.2159 0.2159)
			(layers "F.Cu" "F.Mask" "F.Paste")
			(net "AGND_P0V975")
			(options
				(clearance outline)
				(anchor circle)
			)
			(primitives
				(gr_poly
					(pts
						(arc
							(start -0.3302 -0.4318)
							(mid -0.402042 -0.402042)
							(end -0.4318 -0.3302)
						)
						(arc
							(start -0.4318 0.3302)
							(mid -0.402042 0.402042)
							(end -0.3302 0.4318)
						)
						(arc
							(start 0.3302 0.4318)
							(mid 0.402042 0.402042)
							(end 0.4318 0.3302)
						)
						(arc
							(start 0.4318 -0.3302)
							(mid 0.402042 -0.402042)
							(end 0.3302 -0.4318)
						)
					)
					(width 0)
					(fill yes)
				)
			)
		)
	)
	(footprint ""
		(layer "F.Cu")
		(at 61.29274 -136.433306 90)
		(property "Reference" "R354"
			(at 0 0 90)
			(layer "F.SilkS")
			(hide yes)
			(effects
				(font
					(size 1.27 1.27)
				)
			)
		)
		(property "Value" "4K7R2F-GP"
			(at 0.064008 -3.993896 90)
			(unlocked yes)
			(layer "F.Fab")
			(hide yes)
			(effects
				(font
					(size 1.016 1.016)
					(thickness 0.1524)
				)
			)
		)
		(property "Device Type" "R402H16"
			(at 0.064008 -5.517896 90)
			(unlocked yes)
			(layer "F.Fab")
			(hide yes)
			(effects
				(font
					(size 1.016 1.016)
					(thickness 0.1524)
				)
			)
		)
		(duplicate_pad_numbers_are_jumpers no)
		(fp_line
			(start 0.508 -0.9398)
			(end -0.508 -0.9398)
			(stroke
				(width 0.1524)
				(type default)
			)
			(layer "F.SilkS")
		)
		(fp_line
			(start -0.508 -0.9398)
			(end -0.508 0.9398)
			(stroke
				(width 0.1524)
				(type default)
			)
			(layer "F.SilkS")
		)
		(fp_rect
			(start -0.508 0.9398)
			(end 0.508 -0.9398)
			(stroke
				(width 0)
				(type default)
			)
			(fill no)
			(layer "F.CrtYd")
		)
		(fp_rect
			(start -0.508 0.9398)
			(end 0.508 -0.9398)
			(stroke
				(width 0)
				(type default)
			)
			(fill no)
			(layer "F.Fab")
		)
		(pad "1" smd custom
			(at 0 -0.4445 90)
			(size 0.1397 0.1397)
			(layers "F.Cu" "F.Mask" "F.Paste")
			(net "SLOTID_0")
			(options
				(clearance outline)
				(anchor circle)
			)
			(primitives
				(gr_poly
					(pts
						(arc
							(start -0.1778 -0.2794)
							(mid -0.249642 -0.249642)
							(end -0.2794 -0.1778)
						)
						(arc
							(start -0.2794 0.1778)
							(mid -0.249642 0.249642)
							(end -0.1778 0.2794)
						)
						(arc
							(start 0.1778 0.2794)
							(mid 0.249642 0.249642)
							(end 0.2794 0.1778)
						)
						(arc
							(start 0.2794 -0.1778)
							(mid 0.249642 -0.249642)
							(end 0.1778 -0.2794)
						)
					)
					(width 0)
					(fill yes)
				)
			)
		)
		(pad "2" smd custom
			(at 0 0.4445 90)
			(size 0.1397 0.1397)
			(layers "F.Cu" "F.Mask" "F.Paste")
			(net "GND")
			(options
				(clearance outline)
				(anchor circle)
			)
			(primitives
				(gr_poly
					(pts
						(arc
							(start -0.1778 -0.2794)
							(mid -0.249642 -0.249642)
							(end -0.2794 -0.1778)
						)
						(arc
							(start -0.2794 0.1778)
							(mid -0.249642 0.249642)
							(end -0.1778 0.2794)
						)
						(arc
							(start 0.1778 0.2794)
							(mid 0.249642 0.249642)
							(end 0.2794 0.1778)
						)
						(arc
							(start 0.2794 -0.1778)
							(mid 0.249642 -0.249642)
							(end 0.1778 -0.2794)
						)
					)
					(width 0)
					(fill yes)
				)
			)
		)
	)
	(footprint ""
		(layer "F.Cu")
		(at 199.7964 -106.172)
		(property "Reference" "C262"
			(at 0 0 0)
			(layer "F.SilkS")
			(hide yes)
			(effects
				(font
					(size 1.27 1.27)
				)
			)
		)
		(property "Value" "SC6K8P50V2KX-GP"
			(at 1.1811 -2.7051 0)
			(unlocked yes)
			(layer "F.Fab")
			(hide yes)
			(effects
				(font
					(size 1.016 1.016)
					(thickness 0.1524)
				)
			)
		)
		(property "Device Type" "C402H22"
			(at 1.1811 -4.2291 0)
			(unlocked yes)
			(layer "F.Fab")
			(hide yes)
			(effects
				(font
					(size 1.016 1.016)
					(thickness 0.1524)
				)
			)
		)
		(duplicate_pad_numbers_are_jumpers no)
		(fp_rect
			(start -0.4318 0.9525)
			(end 0.4318 -0.9525)
			(stroke
				(width 0)
				(type default)
			)
			(fill no)
			(layer "F.CrtYd")
		)
		(fp_rect
			(start -0.4318 0.9525)
			(end 0.4318 -0.9525)
			(stroke
				(width 0)
				(type default)
			)
			(fill no)
			(layer "F.Fab")
		)
		(pad "1" smd custom
			(at 0 -0.4445)
			(size 0.1524 0.1524)
			(layers "F.Cu" "F.Mask" "F.Paste")
			(net "P0V975")
			(options
				(clearance outline)
				(anchor circle)
			)
			(primitives
				(gr_poly
					(pts
						(arc
							(start 0.3048 -0.2032)
							(mid 0.275042 -0.275042)
							(end 0.2032 -0.3048)
						)
						(arc
							(start -0.2032 -0.3048)
							(mid -0.275042 -0.275042)
							(end -0.3048 -0.2032)
						)
						(arc
							(start -0.3048 0.2032)
							(mid -0.275042 0.275042)
							(end -0.2032 0.3048)
						)
						(arc
							(start 0.2032 0.3048)
							(mid 0.275042 0.275042)
							(end 0.3048 0.2032)
						)
					)
					(width 0)
					(fill yes)
				)
			)
		)
		(pad "2" smd custom
			(at 0 0.4445)
			(size 0.1524 0.1524)
			(layers "F.Cu" "F.Mask" "F.Paste")
			(net "GND")
			(options
				(clearance outline)
				(anchor circle)
			)
			(primitives
				(gr_poly
					(pts
						(arc
							(start 0.3048 -0.2032)
							(mid 0.275042 -0.275042)
							(end 0.2032 -0.3048)
						)
						(arc
							(start -0.2032 -0.3048)
							(mid -0.275042 -0.275042)
							(end -0.3048 -0.2032)
						)
						(arc
							(start -0.3048 0.2032)
							(mid -0.275042 0.275042)
							(end -0.2032 0.3048)
						)
						(arc
							(start 0.2032 0.3048)
							(mid 0.275042 0.275042)
							(end 0.3048 0.2032)
						)
					)
					(width 0)
					(fill yes)
				)
			)
		)
	)
	(footprint ""
		(layer "F.Cu")
		(at 183.035702 -81.670906)
		(property "Reference" "TP157"
			(at 0 0 0)
			(layer "F.SilkS")
			(hide yes)
			(effects
				(font
					(size 1.27 1.27)
				)
			)
		)
		(property "Value" "TPAD28-2-GP"
			(at -0.0127 -1.6637 0)
			(unlocked yes)
			(layer "F.Fab")
			(hide yes)
			(effects
				(font
					(size 1.016 1.016)
					(thickness 0.1524)
				)
			)
		)
		(property "Device Type" "TPAD28"
			(at -0.0127 -3.1877 0)
			(unlocked yes)
			(layer "F.Fab")
			(hide yes)
			(effects
				(font
					(size 1.016 1.016)
					(thickness 0.1524)
				)
			)
		)
		(duplicate_pad_numbers_are_jumpers no)
		(fp_poly
			(pts
				(arc
					(start 0.3556 0)
					(mid -0.3556 0)
					(end 0.3556 0)
				)
			)
			(stroke
				(width 0)
				(type default)
			)
			(fill no)
			(layer "F.CrtYd")
		)
		(fp_poly
			(pts
				(arc
					(start 0.6096 0)
					(mid -0.6096 0)
					(end 0.6096 0)
				)
			)
			(stroke
				(width 0)
				(type default)
			)
			(fill no)
			(layer "F.Fab")
		)
		(pad "1" smd circle
			(at 0 0)
			(size 0.7112 0.7112)
			(layers "F.Cu" "F.Mask" "F.Paste")
			(net "SPARE1")
		)
	)
	(footprint ""
		(layer "F.Cu")
		(at 204.6224 -48.2854 180)
		(property "Reference" "R629"
			(at 0 0 180)
			(layer "F.SilkS")
			(hide yes)
			(effects
				(font
					(size 1.27 1.27)
				)
			)
		)
		(property "Value" "4K7R2F-GP"
			(at 0.064008 -3.993896 180)
			(unlocked yes)
			(layer "F.Fab")
			(hide yes)
			(effects
				(font
					(size 1.016 1.016)
					(thickness 0.1524)
				)
			)
		)
		(property "Device Type" "R402H16"
			(at 0.064008 -5.517896 180)
			(unlocked yes)
			(layer "F.Fab")
			(hide yes)
			(effects
				(font
					(size 1.016 1.016)
					(thickness 0.1524)
				)
			)
		)
		(duplicate_pad_numbers_are_jumpers no)
		(fp_line
			(start 0.508 -0.9398)
			(end -0.508 -0.9398)
			(stroke
				(width 0.1524)
				(type default)
			)
			(layer "F.SilkS")
		)
		(fp_line
			(start -0.508 -0.9398)
			(end -0.508 0.9398)
			(stroke
				(width 0.1524)
				(type default)
			)
			(layer "F.SilkS")
		)
		(fp_rect
			(start -0.508 0.9398)
			(end 0.508 -0.9398)
			(stroke
				(width 0)
				(type default)
			)
			(fill no)
			(layer "F.CrtYd")
		)
		(fp_rect
			(start -0.508 0.9398)
			(end 0.508 -0.9398)
			(stroke
				(width 0)
				(type default)
			)
			(fill no)
			(layer "F.Fab")
		)
		(pad "1" smd custom
			(at 0 -0.4445 180)
			(size 0.1397 0.1397)
			(layers "F.Cu" "F.Mask" "F.Paste")
			(net "P1V8")
			(options
				(clearance outline)
				(anchor circle)
			)
			(primitives
				(gr_poly
					(pts
						(arc
							(start -0.1778 -0.2794)
							(mid -0.249642 -0.249642)
							(end -0.2794 -0.1778)
						)
						(arc
							(start -0.2794 0.1778)
							(mid -0.249642 0.249642)
							(end -0.1778 0.2794)
						)
						(arc
							(start 0.1778 0.2794)
							(mid 0.249642 0.249642)
							(end 0.2794 0.1778)
						)
						(arc
							(start 0.2794 -0.1778)
							(mid 0.249642 -0.249642)
							(end 0.1778 -0.2794)
						)
					)
					(width 0)
					(fill yes)
				)
			)
		)
		(pad "2" smd custom
			(at 0 0.4445 180)
			(size 0.1397 0.1397)
			(layers "F.Cu" "F.Mask" "F.Paste")
			(net "ICE1_TRST#")
			(options
				(clearance outline)
				(anchor circle)
			)
			(primitives
				(gr_poly
					(pts
						(arc
							(start -0.1778 -0.2794)
							(mid -0.249642 -0.249642)
							(end -0.2794 -0.1778)
						)
						(arc
							(start -0.2794 0.1778)
							(mid -0.249642 0.249642)
							(end -0.1778 0.2794)
						)
						(arc
							(start 0.1778 0.2794)
							(mid 0.249642 0.249642)
							(end 0.2794 0.1778)
						)
						(arc
							(start 0.2794 -0.1778)
							(mid 0.249642 -0.249642)
							(end 0.1778 -0.2794)
						)
					)
					(width 0)
					(fill yes)
				)
			)
		)
	)
	(footprint ""
		(layer "F.Cu")
		(at 186.0804 -88.1126)
		(property "Reference" "TP158"
			(at 0 0 0)
			(layer "F.SilkS")
			(hide yes)
			(effects
				(font
					(size 1.27 1.27)
				)
			)
		)
		(property "Value" "TPAD28-2-GP"
			(at -0.0127 -1.6637 0)
			(unlocked yes)
			(layer "F.Fab")
			(hide yes)
			(effects
				(font
					(size 1.016 1.016)
					(thickness 0.1524)
				)
			)
		)
		(property "Device Type" "TPAD28"
			(at -0.0127 -3.1877 0)
			(unlocked yes)
			(layer "F.Fab")
			(hide yes)
			(effects
				(font
					(size 1.016 1.016)
					(thickness 0.1524)
				)
			)
		)
		(duplicate_pad_numbers_are_jumpers no)
		(fp_poly
			(pts
				(arc
					(start 0.3556 0)
					(mid -0.3556 0)
					(end 0.3556 0)
				)
			)
			(stroke
				(width 0)
				(type default)
			)
			(fill no)
			(layer "F.CrtYd")
		)
		(fp_poly
			(pts
				(arc
					(start 0.6096 0)
					(mid -0.6096 0)
					(end 0.6096 0)
				)
			)
			(stroke
				(width 0)
				(type default)
			)
			(fill no)
			(layer "F.Fab")
		)
		(pad "1" smd circle
			(at 0 0)
			(size 0.7112 0.7112)
			(layers "F.Cu" "F.Mask" "F.Paste")
			(net "SPARE2")
		)
	)
	(footprint ""
		(layer "F.Cu")
		(at 111.450374 -14.464538 -90)
		(property "Reference" "R458"
			(at 0 0 270)
			(layer "F.SilkS")
			(hide yes)
			(effects
				(font
					(size 1.27 1.27)
				)
			)
		)
		(property "Value" "86K6R2F-GP"
			(at 0.064008 -3.993896 270)
			(unlocked yes)
			(layer "F.Fab")
			(hide yes)
			(effects
				(font
					(size 1.016 1.016)
					(thickness 0.1524)
				)
			)
		)
		(property "Device Type" "R402H16"
			(at 0.064008 -5.517896 270)
			(unlocked yes)
			(layer "F.Fab")
			(hide yes)
			(effects
				(font
					(size 1.016 1.016)
					(thickness 0.1524)
				)
			)
		)
		(duplicate_pad_numbers_are_jumpers no)
		(fp_line
			(start -0.508 -0.9398)
			(end -0.508 0.9398)
			(stroke
				(width 0.1524)
				(type default)
			)
			(layer "F.SilkS")
		)
		(fp_line
			(start 0.508 -0.9398)
			(end -0.508 -0.9398)
			(stroke
				(width 0.1524)
				(type default)
			)
			(layer "F.SilkS")
		)
		(fp_rect
			(start -0.508 0.9398)
			(end 0.508 -0.9398)
			(stroke
				(width 0)
				(type default)
			)
			(fill no)
			(layer "F.CrtYd")
		)
		(fp_rect
			(start -0.508 0.9398)
			(end 0.508 -0.9398)
			(stroke
				(width 0)
				(type default)
			)
			(fill no)
			(layer "F.Fab")
		)
		(pad "1" smd custom
			(at 0 -0.4445 270)
			(size 0.1397 0.1397)
			(layers "F.Cu" "F.Mask" "F.Paste")
			(net "MB0_PSET_R")
			(options
				(clearance outline)
				(anchor circle)
			)
			(primitives
				(gr_poly
					(pts
						(arc
							(start -0.1778 -0.2794)
							(mid -0.249642 -0.249642)
							(end -0.2794 -0.1778)
						)
						(arc
							(start -0.2794 0.1778)
							(mid -0.249642 0.249642)
							(end -0.1778 0.2794)
						)
						(arc
							(start 0.1778 0.2794)
							(mid 0.249642 0.249642)
							(end 0.2794 0.1778)
						)
						(arc
							(start 0.2794 -0.1778)
							(mid 0.249642 -0.249642)
							(end 0.1778 -0.2794)
						)
					)
					(width 0)
					(fill yes)
				)
			)
		)
		(pad "2" smd custom
			(at 0 0.4445 270)
			(size 0.1397 0.1397)
			(layers "F.Cu" "F.Mask" "F.Paste")
			(net "AGND_CURRENT_MON")
			(options
				(clearance outline)
				(anchor circle)
			)
			(primitives
				(gr_poly
					(pts
						(arc
							(start -0.1778 -0.2794)
							(mid -0.249642 -0.249642)
							(end -0.2794 -0.1778)
						)
						(arc
							(start -0.2794 0.1778)
							(mid -0.249642 0.249642)
							(end -0.1778 0.2794)
						)
						(arc
							(start 0.1778 0.2794)
							(mid 0.249642 0.249642)
							(end 0.2794 0.1778)
						)
						(arc
							(start 0.2794 -0.1778)
							(mid 0.249642 -0.249642)
							(end 0.1778 -0.2794)
						)
					)
					(width 0)
					(fill yes)
				)
			)
		)
	)
	(footprint ""
		(layer "F.Cu")
		(at 198.755 -49.9872)
		(property "Reference" "TP139"
			(at 0 0 0)
			(layer "F.SilkS")
			(hide yes)
			(effects
				(font
					(size 1.27 1.27)
				)
			)
		)
		(property "Value" "TPAD28-2-GP"
			(at -0.0127 -1.6637 0)
			(unlocked yes)
			(layer "F.Fab")
			(hide yes)
			(effects
				(font
					(size 1.016 1.016)
					(thickness 0.1524)
				)
			)
		)
		(property "Device Type" "TPAD28"
			(at -0.0127 -3.1877 0)
			(unlocked yes)
			(layer "F.Fab")
			(hide yes)
			(effects
				(font
					(size 1.016 1.016)
					(thickness 0.1524)
				)
			)
		)
		(duplicate_pad_numbers_are_jumpers no)
		(fp_poly
			(pts
				(arc
					(start 0.3556 0)
					(mid -0.3556 0)
					(end 0.3556 0)
				)
			)
			(stroke
				(width 0)
				(type default)
			)
			(fill no)
			(layer "F.CrtYd")
		)
		(fp_poly
			(pts
				(arc
					(start 0.6096 0)
					(mid -0.6096 0)
					(end 0.6096 0)
				)
			)
			(stroke
				(width 0)
				(type default)
			)
			(fill no)
			(layer "F.Fab")
		)
		(pad "1" smd circle
			(at 0 0)
			(size 0.7112 0.7112)
			(layers "F.Cu" "F.Mask" "F.Paste")
			(net "ICE0_TRST#")
		)
	)
	(footprint ""
		(layer "F.Cu")
		(at 22.014942 -129.1082 180)
		(property "Reference" "R213"
			(at 0 0 180)
			(layer "F.SilkS")
			(hide yes)
			(effects
				(font
					(size 1.27 1.27)
				)
			)
		)
		(property "Value" "120R2F-GP"
			(at 0.064008 -3.993896 180)
			(unlocked yes)
			(layer "F.Fab")
			(hide yes)
			(effects
				(font
					(size 1.016 1.016)
					(thickness 0.1524)
				)
			)
		)
		(property "Device Type" "R402H16"
			(at 0.064008 -5.517896 180)
			(unlocked yes)
			(layer "F.Fab")
			(hide yes)
			(effects
				(font
					(size 1.016 1.016)
					(thickness 0.1524)
				)
			)
		)
		(duplicate_pad_numbers_are_jumpers no)
		(fp_line
			(start 0.508 -0.9398)
			(end -0.508 -0.9398)
			(stroke
				(width 0.1524)
				(type default)
			)
			(layer "F.SilkS")
		)
		(fp_line
			(start -0.508 -0.9398)
			(end -0.508 0.9398)
			(stroke
				(width 0.1524)
				(type default)
			)
			(layer "F.SilkS")
		)
		(fp_rect
			(start -0.508 0.9398)
			(end 0.508 -0.9398)
			(stroke
				(width 0)
				(type default)
			)
			(fill no)
			(layer "F.CrtYd")
		)
		(fp_rect
			(start -0.508 0.9398)
			(end 0.508 -0.9398)
			(stroke
				(width 0)
				(type default)
			)
			(fill no)
			(layer "F.Fab")
		)
		(pad "1" smd custom
			(at 0 -0.4445 180)
			(size 0.1397 0.1397)
			(layers "F.Cu" "F.Mask" "F.Paste")
			(net "GND")
			(options
				(clearance outline)
				(anchor circle)
			)
			(primitives
				(gr_poly
					(pts
						(arc
							(start -0.1778 -0.2794)
							(mid -0.249642 -0.249642)
							(end -0.2794 -0.1778)
						)
						(arc
							(start -0.2794 0.1778)
							(mid -0.249642 0.249642)
							(end -0.1778 0.2794)
						)
						(arc
							(start 0.1778 0.2794)
							(mid 0.249642 0.249642)
							(end 0.2794 0.1778)
						)
						(arc
							(start 0.2794 -0.1778)
							(mid 0.249642 -0.249642)
							(end 0.1778 -0.2794)
						)
					)
					(width 0)
					(fill yes)
				)
			)
		)
		(pad "2" smd custom
			(at 0 0.4445 180)
			(size 0.1397 0.1397)
			(layers "F.Cu" "F.Mask" "F.Paste")
			(net "DDR4_ALERT")
			(options
				(clearance outline)
				(anchor circle)
			)
			(primitives
				(gr_poly
					(pts
						(arc
							(start -0.1778 -0.2794)
							(mid -0.249642 -0.249642)
							(end -0.2794 -0.1778)
						)
						(arc
							(start -0.2794 0.1778)
							(mid -0.249642 0.249642)
							(end -0.1778 0.2794)
						)
						(arc
							(start 0.1778 0.2794)
							(mid 0.249642 0.249642)
							(end 0.2794 0.1778)
						)
						(arc
							(start 0.2794 -0.1778)
							(mid 0.249642 -0.249642)
							(end 0.1778 -0.2794)
						)
					)
					(width 0)
					(fill yes)
				)
			)
		)
	)
)
